(kicad_pcb
	(version 20260206)
	(generator "pcbnew")
	(generator_version "10.0")
	(general
		(thickness 1.6)
		(legacy_teardrops no)
	)
	(paper "A4")
	(title_block
		(title "15969-1a.1015WZS0858.brd")
		(comment 1 "Tioga Pass / footprints 123-129 of 295")
	)
	(layers
		(0 "F.Cu" signal "TOP")
		(4 "In1.Cu" signal "L2GND")
		(6 "In2.Cu" signal "L3")
		(8 "In3.Cu" signal "L4")
		(10 "In4.Cu" signal "L5GND")
		(2 "B.Cu" signal "BOTTOM")
		(9 "F.Adhes" user "F.Adhesive")
		(11 "B.Adhes" user "B.Adhesive")
		(13 "F.Paste" user "Package Geometry/Pastemask Top")
		(15 "B.Paste" user "Package Geometry/Pastemask Bottom")
		(5 "F.SilkS" user "Ref Des/Silkscreen Top")
		(7 "B.SilkS" user "Ref Des/Silkscreen Bottom")
		(1 "F.Mask" user "Board Geometry/Soldermask Top")
		(3 "B.Mask" user "Board Geometry/Soldermask Bottom")
		(17 "Dwgs.User" user "User.Drawings")
		(19 "Cmts.User" user "User.Comments")
		(21 "Eco1.User" user "User.Eco1")
		(23 "Eco2.User" user "User.Eco2")
		(25 "Edge.Cuts" user "Board Geometry/Outline")
		(27 "Margin" user)
		(31 "F.CrtYd" user "Package Geometry/Place Bound Top")
		(29 "B.CrtYd" user "Package Geometry/Place Bound Bottom")
		(35 "F.Fab" user "Ref Des/Assembly Top")
		(33 "B.Fab" user "Ref Des/Assembly Bottom")
	)
	(footprint ""
		(layer "F.Cu")
		(at 30.21584 -24.06142 180)
		(property "Reference" "R34"
			(at 0 0 180)
			(layer "F.SilkS")
			(hide yes)
			(effects
				(font
					(size 1.27 1.27)
				)
			)
		)
		(property "Value" "0R2F-1-GP"
			(at 0.064008 -3.993896 180)
			(unlocked yes)
			(layer "F.Fab")
			(hide yes)
			(effects
				(font
					(size 1.016 1.016)
					(thickness 0.1524)
				)
			)
		)
		(property "Device Type" "R402H16"
			(at 0.064008 -5.517896 180)
			(unlocked yes)
			(layer "F.Fab")
			(hide yes)
			(effects
				(font
					(size 1.016 1.016)
					(thickness 0.1524)
				)
			)
		)
		(duplicate_pad_numbers_are_jumpers no)
		(fp_line
			(start 0.508 -0.9398)
			(end -0.508 -0.9398)
			(stroke
				(width 0.1524)
				(type default)
			)
			(layer "F.SilkS")
		)
		(fp_line
			(start -0.508 -0.9398)
			(end -0.508 0.9398)
			(stroke
				(width 0.1524)
				(type default)
			)
			(layer "F.SilkS")
		)
		(fp_rect
			(start -0.508 0.9398)
			(end 0.508 -0.9398)
			(stroke
				(width 0)
				(type default)
			)
			(fill no)
			(layer "F.CrtYd")
		)
		(fp_rect
			(start -0.508 0.9398)
			(end 0.508 -0.9398)
			(stroke
				(width 0)
				(type default)
			)
			(fill no)
			(layer "F.Fab")
		)
		(pad "1" smd custom
			(at 0 -0.4445 180)
			(size 0.1397 0.1397)
			(layers "F.Cu" "F.Mask" "F.Paste")
			(net "SMCLK_BMC_SLOT3")
			(options
				(clearance outline)
				(anchor circle)
			)
			(primitives
				(gr_poly
					(pts
						(arc
							(start -0.1778 -0.2794)
							(mid -0.249642 -0.249642)
							(end -0.2794 -0.1778)
						)
						(arc
							(start -0.2794 0.1778)
							(mid -0.249642 0.249642)
							(end -0.1778 0.2794)
						)
						(arc
							(start 0.1778 0.2794)
							(mid 0.249642 0.249642)
							(end 0.2794 0.1778)
						)
						(arc
							(start 0.2794 -0.1778)
							(mid 0.249642 -0.249642)
							(end 0.1778 -0.2794)
						)
					)
					(width 0)
					(fill yes)
				)
			)
		)
		(pad "2" smd custom
			(at 0 0.4445 180)
			(size 0.1397 0.1397)
			(layers "F.Cu" "F.Mask" "F.Paste")
			(net "SMCLK_BMC_SLOT3_R")
			(options
				(clearance outline)
				(anchor circle)
			)
			(primitives
				(gr_poly
					(pts
						(arc
							(start -0.1778 -0.2794)
							(mid -0.249642 -0.249642)
							(end -0.2794 -0.1778)
						)
						(arc
							(start -0.2794 0.1778)
							(mid -0.249642 0.249642)
							(end -0.1778 0.2794)
						)
						(arc
							(start 0.1778 0.2794)
							(mid 0.249642 0.249642)
							(end 0.2794 0.1778)
						)
						(arc
							(start 0.2794 -0.1778)
							(mid 0.249642 -0.249642)
							(end 0.1778 -0.2794)
						)
					)
					(width 0)
					(fill yes)
				)
			)
		)
	)
	(footprint ""
		(layer "F.Cu")
		(at 37.9222 -23.6728 -90)
		(property "Reference" "C20"
			(at 0 0 270)
			(layer "F.SilkS")
			(hide yes)
			(effects
				(font
					(size 1.27 1.27)
				)
			)
		)
		(property "Value" "SC10U6D3V3MX-7-GP-U"
			(at 0 -2.8194 270)
			(unlocked yes)
			(layer "F.Fab")
			(hide yes)
			(effects
				(font
					(size 1.016 1.016)
					(thickness 0.1524)
				)
			)
		)
		(property "Device Type" "C603H40"
			(at 0 -4.3434 270)
			(unlocked yes)
			(layer "F.Fab")
			(hide yes)
			(effects
				(font
					(size 1.016 1.016)
					(thickness 0.1524)
				)
			)
		)
		(duplicate_pad_numbers_are_jumpers no)
		(fp_line
			(start 0.508 0)
			(end -0.508 0)
			(stroke
				(width 0.2032)
				(type default)
			)
			(layer "F.SilkS")
		)
		(fp_rect
			(start -0.5842 1.3335)
			(end 0.5842 -1.3335)
			(stroke
				(width 0)
				(type default)
			)
			(fill no)
			(layer "F.CrtYd")
		)
		(fp_rect
			(start -0.5842 1.3335)
			(end 0.5842 -1.3335)
			(stroke
				(width 0)
				(type default)
			)
			(fill no)
			(layer "F.Fab")
		)
		(pad "1" smd custom
			(at 0 -0.762 270)
			(size 0.2159 0.2159)
			(layers "F.Cu" "F.Mask" "F.Paste")
			(net "P3V3_STBY")
			(options
				(clearance outline)
				(anchor circle)
			)
			(primitives
				(gr_poly
					(pts
						(arc
							(start -0.3302 -0.4318)
							(mid -0.402042 -0.402042)
							(end -0.4318 -0.3302)
						)
						(arc
							(start -0.4318 0.3302)
							(mid -0.402042 0.402042)
							(end -0.3302 0.4318)
						)
						(arc
							(start 0.3302 0.4318)
							(mid 0.402042 0.402042)
							(end 0.4318 0.3302)
						)
						(arc
							(start 0.4318 -0.3302)
							(mid 0.402042 -0.402042)
							(end 0.3302 -0.4318)
						)
					)
					(width 0)
					(fill yes)
				)
			)
		)
		(pad "2" smd custom
			(at 0 0.762 270)
			(size 0.2159 0.2159)
			(layers "F.Cu" "F.Mask" "F.Paste")
			(net "GND")
			(options
				(clearance outline)
				(anchor circle)
			)
			(primitives
				(gr_poly
					(pts
						(arc
							(start -0.3302 -0.4318)
							(mid -0.402042 -0.402042)
							(end -0.4318 -0.3302)
						)
						(arc
							(start -0.4318 0.3302)
							(mid -0.402042 0.402042)
							(end -0.3302 0.4318)
						)
						(arc
							(start 0.3302 0.4318)
							(mid 0.402042 0.402042)
							(end 0.4318 0.3302)
						)
						(arc
							(start 0.4318 -0.3302)
							(mid 0.402042 -0.402042)
							(end 0.3302 -0.4318)
						)
					)
					(width 0)
					(fill yes)
				)
			)
		)
	)
	(footprint ""
		(layer "F.Cu")
		(at 119.5324 -15.5956 90)
		(property "Reference" "R108"
			(at 0 0 90)
			(layer "F.SilkS")
			(hide yes)
			(effects
				(font
					(size 1.27 1.27)
				)
			)
		)
		(property "Value" "4K7R2F-GP"
			(at 0.064008 -3.993896 90)
			(unlocked yes)
			(layer "F.Fab")
			(hide yes)
			(effects
				(font
					(size 1.016 1.016)
					(thickness 0.1524)
				)
			)
		)
		(property "Device Type" "R402H16"
			(at 0.064008 -5.517896 90)
			(unlocked yes)
			(layer "F.Fab")
			(hide yes)
			(effects
				(font
					(size 1.016 1.016)
					(thickness 0.1524)
				)
			)
		)
		(duplicate_pad_numbers_are_jumpers no)
		(fp_line
			(start 0.508 -0.9398)
			(end -0.508 -0.9398)
			(stroke
				(width 0.1524)
				(type default)
			)
			(layer "F.SilkS")
		)
		(fp_line
			(start -0.508 -0.9398)
			(end -0.508 0.9398)
			(stroke
				(width 0.1524)
				(type default)
			)
			(layer "F.SilkS")
		)
		(fp_rect
			(start -0.508 0.9398)
			(end 0.508 -0.9398)
			(stroke
				(width 0)
				(type default)
			)
			(fill no)
			(layer "F.CrtYd")
		)
		(fp_rect
			(start -0.508 0.9398)
			(end 0.508 -0.9398)
			(stroke
				(width 0)
				(type default)
			)
			(fill no)
			(layer "F.Fab")
		)
		(pad "1" smd custom
			(at 0 -0.4445 90)
			(size 0.1397 0.1397)
			(layers "F.Cu" "F.Mask" "F.Paste")
			(net "P3V3_STBY")
			(options
				(clearance outline)
				(anchor circle)
			)
			(primitives
				(gr_poly
					(pts
						(arc
							(start -0.1778 -0.2794)
							(mid -0.249642 -0.249642)
							(end -0.2794 -0.1778)
						)
						(arc
							(start -0.2794 0.1778)
							(mid -0.249642 0.249642)
							(end -0.1778 0.2794)
						)
						(arc
							(start 0.1778 0.2794)
							(mid 0.249642 0.249642)
							(end 0.2794 0.1778)
						)
						(arc
							(start 0.2794 -0.1778)
							(mid 0.249642 -0.249642)
							(end 0.1778 -0.2794)
						)
					)
					(width 0)
					(fill yes)
				)
			)
		)
		(pad "2" smd custom
			(at 0 0.4445 90)
			(size 0.1397 0.1397)
			(layers "F.Cu" "F.Mask" "F.Paste")
			(net "PCIE_SLOT2_PRSNT2_4_N")
			(options
				(clearance outline)
				(anchor circle)
			)
			(primitives
				(gr_poly
					(pts
						(arc
							(start -0.1778 -0.2794)
							(mid -0.249642 -0.249642)
							(end -0.2794 -0.1778)
						)
						(arc
							(start -0.2794 0.1778)
							(mid -0.249642 0.249642)
							(end -0.1778 0.2794)
						)
						(arc
							(start 0.1778 0.2794)
							(mid 0.249642 0.249642)
							(end 0.2794 0.1778)
						)
						(arc
							(start 0.2794 -0.1778)
							(mid 0.249642 -0.249642)
							(end 0.1778 -0.2794)
						)
					)
					(width 0)
					(fill yes)
				)
			)
		)
	)
	(footprint ""
		(layer "F.Cu")
		(at 37.719 -24.7396 -90)
		(property "Reference" "C21"
			(at 0 0 270)
			(layer "F.SilkS")
			(hide yes)
			(effects
				(font
					(size 1.27 1.27)
				)
			)
		)
		(property "Value" "SCD1U16V2KX-3GP"
			(at 1.1811 -2.7051 270)
			(unlocked yes)
			(layer "F.Fab")
			(hide yes)
			(effects
				(font
					(size 1.016 1.016)
					(thickness 0.1524)
				)
			)
		)
		(property "Device Type" "C402H22"
			(at 1.1811 -4.2291 270)
			(unlocked yes)
			(layer "F.Fab")
			(hide yes)
			(effects
				(font
					(size 1.016 1.016)
					(thickness 0.1524)
				)
			)
		)
		(duplicate_pad_numbers_are_jumpers no)
		(fp_rect
			(start -0.4318 0.9525)
			(end 0.4318 -0.9525)
			(stroke
				(width 0)
				(type default)
			)
			(fill no)
			(layer "F.CrtYd")
		)
		(fp_rect
			(start -0.4318 0.9525)
			(end 0.4318 -0.9525)
			(stroke
				(width 0)
				(type default)
			)
			(fill no)
			(layer "F.Fab")
		)
		(pad "1" smd custom
			(at 0 -0.4445 270)
			(size 0.1524 0.1524)
			(layers "F.Cu" "F.Mask" "F.Paste")
			(net "P3V3_STBY")
			(options
				(clearance outline)
				(anchor circle)
			)
			(primitives
				(gr_poly
					(pts
						(arc
							(start 0.3048 -0.2032)
							(mid 0.275042 -0.275042)
							(end 0.2032 -0.3048)
						)
						(arc
							(start -0.2032 -0.3048)
							(mid -0.275042 -0.275042)
							(end -0.3048 -0.2032)
						)
						(arc
							(start -0.3048 0.2032)
							(mid -0.275042 0.275042)
							(end -0.2032 0.3048)
						)
						(arc
							(start 0.2032 0.3048)
							(mid 0.275042 0.275042)
							(end 0.3048 0.2032)
						)
					)
					(width 0)
					(fill yes)
				)
			)
		)
		(pad "2" smd custom
			(at 0 0.4445 270)
			(size 0.1524 0.1524)
			(layers "F.Cu" "F.Mask" "F.Paste")
			(net "GND")
			(options
				(clearance outline)
				(anchor circle)
			)
			(primitives
				(gr_poly
					(pts
						(arc
							(start 0.3048 -0.2032)
							(mid 0.275042 -0.275042)
							(end 0.2032 -0.3048)
						)
						(arc
							(start -0.2032 -0.3048)
							(mid -0.275042 -0.275042)
							(end -0.3048 -0.2032)
						)
						(arc
							(start -0.3048 0.2032)
							(mid -0.275042 0.275042)
							(end -0.2032 0.3048)
						)
						(arc
							(start 0.2032 0.3048)
							(mid 0.275042 0.275042)
							(end 0.3048 0.2032)
						)
					)
					(width 0)
					(fill yes)
				)
			)
		)
	)
	(footprint ""
		(layer "F.Cu")
		(at 17.6022 -32.0548 180)
		(property "Reference" "C25"
			(at 0 0 180)
			(layer "F.SilkS")
			(hide yes)
			(effects
				(font
					(size 1.27 1.27)
				)
			)
		)
		(property "Value" "SCD1U25V3KX-GP"
			(at 0 -2.8194 180)
			(unlocked yes)
			(layer "F.Fab")
			(hide yes)
			(effects
				(font
					(size 1.016 1.016)
					(thickness 0.1524)
				)
			)
		)
		(property "Device Type" "C603H36"
			(at 0 -4.3434 180)
			(unlocked yes)
			(layer "F.Fab")
			(hide yes)
			(effects
				(font
					(size 1.016 1.016)
					(thickness 0.1524)
				)
			)
		)
		(duplicate_pad_numbers_are_jumpers no)
		(fp_line
			(start 0.508 0)
			(end -0.508 0)
			(stroke
				(width 0.2032)
				(type default)
			)
			(layer "F.SilkS")
		)
		(fp_rect
			(start -0.5842 1.3335)
			(end 0.5842 -1.3335)
			(stroke
				(width 0)
				(type default)
			)
			(fill no)
			(layer "F.CrtYd")
		)
		(fp_rect
			(start -0.5842 1.3335)
			(end 0.5842 -1.3335)
			(stroke
				(width 0)
				(type default)
			)
			(fill no)
			(layer "F.Fab")
		)
		(pad "1" smd custom
			(at 0 -0.762 180)
			(size 0.2159 0.2159)
			(layers "F.Cu" "F.Mask" "F.Paste")
			(net "P12V_SLOT3")
			(options
				(clearance outline)
				(anchor circle)
			)
			(primitives
				(gr_poly
					(pts
						(arc
							(start -0.3302 -0.4318)
							(mid -0.402042 -0.402042)
							(end -0.4318 -0.3302)
						)
						(arc
							(start -0.4318 0.3302)
							(mid -0.402042 0.402042)
							(end -0.3302 0.4318)
						)
						(arc
							(start 0.3302 0.4318)
							(mid 0.402042 0.402042)
							(end 0.4318 0.3302)
						)
						(arc
							(start 0.4318 -0.3302)
							(mid 0.402042 -0.402042)
							(end 0.3302 -0.4318)
						)
					)
					(width 0)
					(fill yes)
				)
			)
		)
		(pad "2" smd custom
			(at 0 0.762 180)
			(size 0.2159 0.2159)
			(layers "F.Cu" "F.Mask" "F.Paste")
			(net "GND")
			(options
				(clearance outline)
				(anchor circle)
			)
			(primitives
				(gr_poly
					(pts
						(arc
							(start -0.3302 -0.4318)
							(mid -0.402042 -0.402042)
							(end -0.4318 -0.3302)
						)
						(arc
							(start -0.4318 0.3302)
							(mid -0.402042 0.402042)
							(end -0.3302 0.4318)
						)
						(arc
							(start 0.3302 0.4318)
							(mid 0.402042 0.402042)
							(end 0.4318 0.3302)
						)
						(arc
							(start 0.4318 -0.3302)
							(mid 0.402042 -0.402042)
							(end 0.3302 -0.4318)
						)
					)
					(width 0)
					(fill yes)
				)
			)
		)
	)
	(footprint ""
		(layer "F.Cu")
		(at 89.5858 -21.1074)
		(property "Reference" "R78"
			(at 0 0 0)
			(layer "F.SilkS")
			(hide yes)
			(effects
				(font
					(size 1.27 1.27)
				)
			)
		)
		(property "Value" "0R2F-1-GP"
			(at 0.064008 -3.993896 0)
			(unlocked yes)
			(layer "F.Fab")
			(hide yes)
			(effects
				(font
					(size 1.016 1.016)
					(thickness 0.1524)
				)
			)
		)
		(property "Device Type" "R402H16"
			(at 0.064008 -5.517896 0)
			(unlocked yes)
			(layer "F.Fab")
			(hide yes)
			(effects
				(font
					(size 1.016 1.016)
					(thickness 0.1524)
				)
			)
		)
		(duplicate_pad_numbers_are_jumpers no)
		(fp_line
			(start -0.508 -0.9398)
			(end -0.508 0.9398)
			(stroke
				(width 0.1524)
				(type default)
			)
			(layer "F.SilkS")
		)
		(fp_line
			(start 0.508 -0.9398)
			(end -0.508 -0.9398)
			(stroke
				(width 0.1524)
				(type default)
			)
			(layer "F.SilkS")
		)
		(fp_rect
			(start -0.508 0.9398)
			(end 0.508 -0.9398)
			(stroke
				(width 0)
				(type default)
			)
			(fill no)
			(layer "F.CrtYd")
		)
		(fp_rect
			(start -0.508 0.9398)
			(end 0.508 -0.9398)
			(stroke
				(width 0)
				(type default)
			)
			(fill no)
			(layer "F.Fab")
		)
		(pad "1" smd custom
			(at 0 -0.4445)
			(size 0.1397 0.1397)
			(layers "F.Cu" "F.Mask" "F.Paste")
			(net "PERST_N_1")
			(options
				(clearance outline)
				(anchor circle)
			)
			(primitives
				(gr_poly
					(pts
						(arc
							(start -0.1778 -0.2794)
							(mid -0.249642 -0.249642)
							(end -0.2794 -0.1778)
						)
						(arc
							(start -0.2794 0.1778)
							(mid -0.249642 0.249642)
							(end -0.1778 0.2794)
						)
						(arc
							(start 0.1778 0.2794)
							(mid 0.249642 0.249642)
							(end 0.2794 0.1778)
						)
						(arc
							(start 0.2794 -0.1778)
							(mid 0.249642 -0.249642)
							(end 0.1778 -0.2794)
						)
					)
					(width 0)
					(fill yes)
				)
			)
		)
		(pad "2" smd custom
			(at 0 0.4445)
			(size 0.1397 0.1397)
			(layers "F.Cu" "F.Mask" "F.Paste")
			(net "PERST_N_1_R")
			(options
				(clearance outline)
				(anchor circle)
			)
			(primitives
				(gr_poly
					(pts
						(arc
							(start -0.1778 -0.2794)
							(mid -0.249642 -0.249642)
							(end -0.2794 -0.1778)
						)
						(arc
							(start -0.2794 0.1778)
							(mid -0.249642 0.249642)
							(end -0.1778 0.2794)
						)
						(arc
							(start 0.1778 0.2794)
							(mid 0.249642 0.249642)
							(end 0.2794 0.1778)
						)
						(arc
							(start 0.2794 -0.1778)
							(mid 0.249642 -0.249642)
							(end 0.1778 -0.2794)
						)
					)
					(width 0)
					(fill yes)
				)
			)
		)
	)
	(footprint ""
		(layer "F.Cu")
		(at 131.6736 -18.8214 -90)
		(property "Reference" "R132"
			(at 0 0 270)
			(layer "F.SilkS")
			(hide yes)
			(effects
				(font
					(size 1.27 1.27)
				)
			)
		)
		(property "Value" "10KR2F-2-GP"
			(at 0.064008 -3.993896 270)
			(unlocked yes)
			(layer "F.Fab")
			(hide yes)
			(effects
				(font
					(size 1.016 1.016)
					(thickness 0.1524)
				)
			)
		)
		(property "Device Type" "R402H16"
			(at 0.064008 -5.517896 270)
			(unlocked yes)
			(layer "F.Fab")
			(hide yes)
			(effects
				(font
					(size 1.016 1.016)
					(thickness 0.1524)
				)
			)
		)
		(duplicate_pad_numbers_are_jumpers no)
		(fp_line
			(start -0.508 -0.9398)
			(end -0.508 0.9398)
			(stroke
				(width 0.1524)
				(type default)
			)
			(layer "F.SilkS")
		)
		(fp_line
			(start 0.508 -0.9398)
			(end -0.508 -0.9398)
			(stroke
				(width 0.1524)
				(type default)
			)
			(layer "F.SilkS")
		)
		(fp_rect
			(start -0.508 0.9398)
			(end 0.508 -0.9398)
			(stroke
				(width 0)
				(type default)
			)
			(fill no)
			(layer "F.CrtYd")
		)
		(fp_rect
			(start -0.508 0.9398)
			(end 0.508 -0.9398)
			(stroke
				(width 0)
				(type default)
			)
			(fill no)
			(layer "F.Fab")
		)
		(pad "1" smd custom
			(at 0 -0.4445 270)
			(size 0.1397 0.1397)
			(layers "F.Cu" "F.Mask" "F.Paste")
			(net "P3V3_STBY")
			(options
				(clearance outline)
				(anchor circle)
			)
			(primitives
				(gr_poly
					(pts
						(arc
							(start -0.1778 -0.2794)
							(mid -0.249642 -0.249642)
							(end -0.2794 -0.1778)
						)
						(arc
							(start -0.2794 0.1778)
							(mid -0.249642 0.249642)
							(end -0.1778 0.2794)
						)
						(arc
							(start 0.1778 0.2794)
							(mid 0.249642 0.249642)
							(end 0.2794 0.1778)
						)
						(arc
							(start 0.2794 -0.1778)
							(mid 0.249642 -0.249642)
							(end 0.1778 -0.2794)
						)
					)
					(width 0)
					(fill yes)
				)
			)
		)
		(pad "2" smd custom
			(at 0 0.4445 270)
			(size 0.1397 0.1397)
			(layers "F.Cu" "F.Mask" "F.Paste")
			(net "GPIO_B_IO1_7")
			(options
				(clearance outline)
				(anchor circle)
			)
			(primitives
				(gr_poly
					(pts
						(arc
							(start -0.1778 -0.2794)
							(mid -0.249642 -0.249642)
							(end -0.2794 -0.1778)
						)
						(arc
							(start -0.2794 0.1778)
							(mid -0.249642 0.249642)
							(end -0.1778 0.2794)
						)
						(arc
							(start 0.1778 0.2794)
							(mid 0.249642 0.249642)
							(end 0.2794 0.1778)
						)
						(arc
							(start 0.2794 -0.1778)
							(mid 0.249642 -0.249642)
							(end 0.1778 -0.2794)
						)
					)
					(width 0)
					(fill yes)
				)
			)
		)
	)
)
